(kicad_pcb
	(version 20260206)
	(generator "pcbnew")
	(generator_version "10.0")
	(general
		(thickness 1.6)
		(legacy_teardrops no)
	)
	(paper "A4")
	(title_block
		(title "04192023_DAF0TMB3IC0_F0TG_MB_C_brd_V02_OCP.brd")
		(comment 1 "Grand Teton / footprints 7633-7641 of 8354")
	)
	(layers
		(0 "F.Cu" signal "TOP")
		(4 "In1.Cu" signal "GND")
		(6 "In2.Cu" signal "IN1")
		(8 "In3.Cu" signal "GND1")
		(10 "In4.Cu" signal "IN2")
		(12 "In5.Cu" signal "GND2")
		(14 "In6.Cu" signal "IN3")
		(16 "In7.Cu" signal "GND3")
		(18 "In8.Cu" signal "VCC")
		(20 "In9.Cu" signal "VCC1")
		(22 "In10.Cu" signal "GND4")
		(24 "In11.Cu" signal "IN4")
		(26 "In12.Cu" signal "GND5")
		(28 "In13.Cu" signal "IN5")
		(30 "In14.Cu" signal "GND6")
		(32 "In15.Cu" signal "IN6")
		(34 "In16.Cu" signal "GND7")
		(2 "B.Cu" signal "BOTTOM")
		(9 "F.Adhes" user "F.Adhesive")
		(11 "B.Adhes" user "B.Adhesive")
		(13 "F.Paste" user "Package Geometry/Pastemask Top")
		(15 "B.Paste" user "Package Geometry/Pastemask Bottom")
		(5 "F.SilkS" user "Ref Des/Silkscreen Top")
		(7 "B.SilkS" user "Ref Des/Silkscreen Bottom")
		(1 "F.Mask" user "Board Geometry/Soldermask Top")
		(3 "B.Mask" user "Board Geometry/Soldermask Bottom")
		(17 "Dwgs.User" user "User.Drawings")
		(19 "Cmts.User" user "User.Comments")
		(21 "Eco1.User" user "User.Eco1")
		(23 "Eco2.User" user "User.Eco2")
		(25 "Edge.Cuts" user "Board Geometry/Outline")
		(27 "Margin" user)
		(31 "F.CrtYd" user "Package Geometry/Place Bound Top")
		(29 "B.CrtYd" user "Package Geometry/Place Bound Bottom")
		(35 "F.Fab" user "Ref Des/Assembly Top")
		(33 "B.Fab" user "Ref Des/Assembly Bottom")
	)
	(footprint ""
		(layer "B.Cu")
		(at 299.265594 -394.29436 180)
		(property "Reference" "R982"
			(at 0 0 0)
			(layer "B.SilkS")
			(hide yes)
			(effects
				(font
					(size 1.27 1.27)
				)
				(justify mirror)
			)
		)
		(property "Value" ""
			(at 0 0 0)
			(layer "B.Fab")
			(effects
				(font
					(size 1.27 1.27)
				)
				(justify mirror)
			)
		)
		(duplicate_pad_numbers_are_jumpers no)
		(fp_line
			(start 0.32512 0.175006)
			(end 0.32512 -0.175006)
			(stroke
				(width 0.1)
				(type default)
			)
			(layer "B.Fab")
		)
		(fp_line
			(start 0.32512 -0.175006)
			(end -0.32512 -0.175006)
			(stroke
				(width 0.1)
				(type default)
			)
			(layer "B.Fab")
		)
		(fp_line
			(start -0.32512 0.175006)
			(end 0.32512 0.175006)
			(stroke
				(width 0.1)
				(type default)
			)
			(layer "B.Fab")
		)
		(fp_line
			(start -0.32512 -0.175006)
			(end -0.32512 0.175006)
			(stroke
				(width 0.1)
				(type default)
			)
			(layer "B.Fab")
		)
		(pad "1" smd rect
			(at 0.2667 0)
			(size 0.3048 0.381)
			(layers "B.Cu" "B.Mask" "B.Paste")
			(net "TEST0_RT_CPU0_P0")
		)
		(pad "2" smd rect
			(at -0.2667 0 180)
			(size 0.3048 0.381)
			(layers "B.Cu" "B.Mask" "B.Paste")
			(net "GND")
		)
	)
	(footprint ""
		(layer "B.Cu")
		(at 171.196 -115.280948)
		(property "Reference" "R992"
			(at 0 0 0)
			(layer "B.SilkS")
			(hide yes)
			(effects
				(font
					(size 1.27 1.27)
				)
				(justify mirror)
			)
		)
		(property "Value" ""
			(at 0 0 0)
			(layer "B.Fab")
			(effects
				(font
					(size 1.27 1.27)
				)
				(justify mirror)
			)
		)
		(duplicate_pad_numbers_are_jumpers no)
		(fp_line
			(start -0.7874 -0.4064)
			(end -0.7874 0.4064)
			(stroke
				(width 0.1524)
				(type default)
			)
			(layer "B.SilkS")
		)
		(fp_line
			(start -0.7874 0.4064)
			(end 0.7874 0.4064)
			(stroke
				(width 0.1524)
				(type default)
			)
			(layer "B.SilkS")
		)
		(fp_line
			(start 0.7874 -0.4064)
			(end -0.7874 -0.4064)
			(stroke
				(width 0.1524)
				(type default)
			)
			(layer "B.SilkS")
		)
		(fp_line
			(start 0.7874 0.4064)
			(end 0.7874 -0.4064)
			(stroke
				(width 0.1524)
				(type default)
			)
			(layer "B.SilkS")
		)
		(fp_line
			(start -0.67945 -0.3048)
			(end -0.67945 0.3048)
			(stroke
				(width 0.1)
				(type default)
			)
			(layer "B.Fab")
		)
		(fp_line
			(start -0.67945 0.3048)
			(end -0.120396 0.3048)
			(stroke
				(width 0.1)
				(type default)
			)
			(layer "B.Fab")
		)
		(fp_line
			(start -0.12065 -0.3048)
			(end -0.67945 -0.3048)
			(stroke
				(width 0.1)
				(type default)
			)
			(layer "B.Fab")
		)
		(fp_line
			(start -0.12065 -0.2794)
			(end -0.12065 -0.3048)
			(stroke
				(width 0.1)
				(type default)
			)
			(layer "B.Fab")
		)
		(fp_line
			(start -0.120396 0.2794)
			(end 0.12065 0.2794)
			(stroke
				(width 0.1)
				(type default)
			)
			(layer "B.Fab")
		)
		(fp_line
			(start -0.120396 0.3048)
			(end -0.120396 0.2794)
			(stroke
				(width 0.1)
				(type default)
			)
			(layer "B.Fab")
		)
		(fp_line
			(start 0.12065 -0.305054)
			(end 0.12065 -0.2794)
			(stroke
				(width 0.1)
				(type default)
			)
			(layer "B.Fab")
		)
		(fp_line
			(start 0.12065 -0.2794)
			(end -0.12065 -0.2794)
			(stroke
				(width 0.1)
				(type default)
			)
			(layer "B.Fab")
		)
		(fp_line
			(start 0.12065 0.2794)
			(end 0.12065 0.3048)
			(stroke
				(width 0.1)
				(type default)
			)
			(layer "B.Fab")
		)
		(fp_line
			(start 0.12065 0.3048)
			(end 0.67945 0.3048)
			(stroke
				(width 0.1)
				(type default)
			)
			(layer "B.Fab")
		)
		(fp_line
			(start 0.67945 -0.305054)
			(end 0.12065 -0.305054)
			(stroke
				(width 0.1)
				(type default)
			)
			(layer "B.Fab")
		)
		(fp_line
			(start 0.67945 0.3048)
			(end 0.67945 -0.305054)
			(stroke
				(width 0.1)
				(type default)
			)
			(layer "B.Fab")
		)
		(pad "1" smd circle
			(at 0.40005 0 180)
			(size 0 0)
			(layers "B.Cu" "B.Mask" "B.Paste")
			(net "FM_SYS_THROTTLE_R_N")
		)
		(pad "2" smd circle
			(at -0.40005 0 180)
			(size 0 0)
			(layers "B.Cu" "B.Mask" "B.Paste")
			(net "FM_SYS_THROTTLE_N")
		)
	)
	(footprint ""
		(layer "B.Cu")
		(at 177.965608 -126.833376 90)
		(property "Reference" "R254"
			(at 0 0 90)
			(layer "B.SilkS")
			(hide yes)
			(effects
				(font
					(size 1.27 1.27)
				)
				(justify mirror)
			)
		)
		(property "Value" ""
			(at 0 0 90)
			(layer "B.Fab")
			(effects
				(font
					(size 1.27 1.27)
				)
				(justify mirror)
			)
		)
		(duplicate_pad_numbers_are_jumpers no)
		(fp_line
			(start 0.7874 -0.4064)
			(end -0.7874 -0.4064)
			(stroke
				(width 0.1524)
				(type default)
			)
			(layer "B.SilkS")
		)
		(fp_line
			(start -0.7874 -0.4064)
			(end -0.7874 0.4064)
			(stroke
				(width 0.1524)
				(type default)
			)
			(layer "B.SilkS")
		)
		(fp_line
			(start 0.7874 0.4064)
			(end 0.7874 -0.4064)
			(stroke
				(width 0.1524)
				(type default)
			)
			(layer "B.SilkS")
		)
		(fp_line
			(start -0.7874 0.4064)
			(end 0.7874 0.4064)
			(stroke
				(width 0.1524)
				(type default)
			)
			(layer "B.SilkS")
		)
		(fp_line
			(start 0.67945 -0.305054)
			(end 0.12065 -0.305054)
			(stroke
				(width 0.1)
				(type default)
			)
			(layer "B.Fab")
		)
		(fp_line
			(start 0.12065 -0.305054)
			(end 0.12065 -0.2794)
			(stroke
				(width 0.1)
				(type default)
			)
			(layer "B.Fab")
		)
		(fp_line
			(start -0.12065 -0.3048)
			(end -0.67945 -0.3048)
			(stroke
				(width 0.1)
				(type default)
			)
			(layer "B.Fab")
		)
		(fp_line
			(start -0.67945 -0.3048)
			(end -0.67945 0.3048)
			(stroke
				(width 0.1)
				(type default)
			)
			(layer "B.Fab")
		)
		(fp_line
			(start 0.12065 -0.2794)
			(end -0.12065 -0.2794)
			(stroke
				(width 0.1)
				(type default)
			)
			(layer "B.Fab")
		)
		(fp_line
			(start -0.12065 -0.2794)
			(end -0.12065 -0.3048)
			(stroke
				(width 0.1)
				(type default)
			)
			(layer "B.Fab")
		)
		(fp_line
			(start 0.12065 0.2794)
			(end 0.12065 0.3048)
			(stroke
				(width 0.1)
				(type default)
			)
			(layer "B.Fab")
		)
		(fp_line
			(start -0.120396 0.2794)
			(end 0.12065 0.2794)
			(stroke
				(width 0.1)
				(type default)
			)
			(layer "B.Fab")
		)
		(fp_line
			(start 0.67945 0.3048)
			(end 0.67945 -0.305054)
			(stroke
				(width 0.1)
				(type default)
			)
			(layer "B.Fab")
		)
		(fp_line
			(start 0.12065 0.3048)
			(end 0.67945 0.3048)
			(stroke
				(width 0.1)
				(type default)
			)
			(layer "B.Fab")
		)
		(fp_line
			(start -0.120396 0.3048)
			(end -0.120396 0.2794)
			(stroke
				(width 0.1)
				(type default)
			)
			(layer "B.Fab")
		)
		(fp_line
			(start -0.67945 0.3048)
			(end -0.120396 0.3048)
			(stroke
				(width 0.1)
				(type default)
			)
			(layer "B.Fab")
		)
		(pad "1" smd circle
			(at 0.40005 0 270)
			(size 0 0)
			(layers "B.Cu" "B.Mask" "B.Paste")
			(net "RST_CPU0_PERST0_N")
		)
		(pad "2" smd circle
			(at -0.40005 0 270)
			(size 0 0)
			(layers "B.Cu" "B.Mask" "B.Paste")
			(net "RST_CPU0_PERST0_R_N")
		)
	)
	(footprint ""
		(layer "B.Cu")
		(at 376.6185 -396.393162 -90)
		(property "Reference" "C1009"
			(at 0 0 90)
			(layer "B.SilkS")
			(hide yes)
			(effects
				(font
					(size 1.27 1.27)
				)
				(justify mirror)
			)
		)
		(property "Value" ""
			(at 0 0 90)
			(layer "B.Fab")
			(effects
				(font
					(size 1.27 1.27)
				)
				(justify mirror)
			)
		)
		(duplicate_pad_numbers_are_jumpers no)
		(fp_line
			(start -0.299974 0.150114)
			(end 0.299974 0.150114)
			(stroke
				(width 0.1)
				(type default)
			)
			(layer "B.Fab")
		)
		(fp_line
			(start 0.299974 0.150114)
			(end 0.299974 -0.150114)
			(stroke
				(width 0.1)
				(type default)
			)
			(layer "B.Fab")
		)
		(fp_line
			(start -0.299974 -0.150114)
			(end -0.299974 0.150114)
			(stroke
				(width 0.1)
				(type default)
			)
			(layer "B.Fab")
		)
		(fp_line
			(start 0.299974 -0.150114)
			(end -0.299974 -0.150114)
			(stroke
				(width 0.1)
				(type default)
			)
			(layer "B.Fab")
		)
		(pad "1" smd rect
			(at 0.2667 0 90)
			(size 0.3048 0.381)
			(layers "B.Cu" "B.Mask" "B.Paste")
			(net "P0V9_CPU0_RT_2D")
		)
		(pad "2" smd rect
			(at -0.2667 0 90)
			(size 0.3048 0.381)
			(layers "B.Cu" "B.Mask" "B.Paste")
			(net "GND")
		)
	)
	(footprint ""
		(layer "B.Cu")
		(at 102.389432 -391.81405 180)
		(property "Reference" "C328"
			(at 0 0 0)
			(layer "B.SilkS")
			(hide yes)
			(effects
				(font
					(size 1.27 1.27)
				)
				(justify mirror)
			)
		)
		(property "Value" ""
			(at 0 0 0)
			(layer "B.Fab")
			(effects
				(font
					(size 1.27 1.27)
				)
				(justify mirror)
			)
		)
		(duplicate_pad_numbers_are_jumpers no)
		(fp_line
			(start 1.524 0.762)
			(end 1.524 -0.762)
			(stroke
				(width 0.1524)
				(type default)
			)
			(layer "B.SilkS")
		)
		(fp_line
			(start 1.524 -0.762)
			(end -1.524 -0.762)
			(stroke
				(width 0.1524)
				(type default)
			)
			(layer "B.SilkS")
		)
		(fp_line
			(start -1.524 0.762)
			(end 1.524 0.762)
			(stroke
				(width 0.1524)
				(type default)
			)
			(layer "B.SilkS")
		)
		(fp_line
			(start -1.524 -0.762)
			(end -1.524 0.762)
			(stroke
				(width 0.1524)
				(type default)
			)
			(layer "B.SilkS")
		)
		(fp_line
			(start 1.1049 0.724916)
			(end -1.1049 0.724916)
			(stroke
				(width 0.1)
				(type default)
			)
			(layer "B.Fab")
		)
		(fp_line
			(start 1.1049 -0.724916)
			(end 1.1049 0.724916)
			(stroke
				(width 0.1)
				(type default)
			)
			(layer "B.Fab")
		)
		(fp_line
			(start -1.1049 0.724916)
			(end -1.1049 -0.724916)
			(stroke
				(width 0.1)
				(type default)
			)
			(layer "B.Fab")
		)
		(fp_line
			(start -1.1049 -0.724916)
			(end 1.1049 -0.724916)
			(stroke
				(width 0.1)
				(type default)
			)
			(layer "B.Fab")
		)
		(pad "1" smd rect
			(at 0.889 0 180)
			(size 1.016 1.27)
			(layers "B.Cu" "B.Mask" "B.Paste")
			(net "P0V9_CPU1_RT1_2A")
		)
		(pad "2" smd rect
			(at -0.889 0 180)
			(size 1.016 1.27)
			(layers "B.Cu" "B.Mask" "B.Paste")
			(net "GND")
		)
	)
	(footprint ""
		(layer "B.Cu")
		(at 238.633 -337.312 180)
		(property "Reference" "R805"
			(at 0 0 0)
			(layer "B.SilkS")
			(hide yes)
			(effects
				(font
					(size 1.27 1.27)
				)
				(justify mirror)
			)
		)
		(property "Value" ""
			(at 0 0 0)
			(layer "B.Fab")
			(effects
				(font
					(size 1.27 1.27)
				)
				(justify mirror)
			)
		)
		(duplicate_pad_numbers_are_jumpers no)
		(fp_line
			(start 0.32512 0.175006)
			(end 0.32512 -0.175006)
			(stroke
				(width 0.1)
				(type default)
			)
			(layer "B.Fab")
		)
		(fp_line
			(start 0.32512 -0.175006)
			(end -0.32512 -0.175006)
			(stroke
				(width 0.1)
				(type default)
			)
			(layer "B.Fab")
		)
		(fp_line
			(start -0.32512 0.175006)
			(end 0.32512 0.175006)
			(stroke
				(width 0.1)
				(type default)
			)
			(layer "B.Fab")
		)
		(fp_line
			(start -0.32512 -0.175006)
			(end -0.32512 0.175006)
			(stroke
				(width 0.1)
				(type default)
			)
			(layer "B.Fab")
		)
		(pad "1" smd rect
			(at 0.2667 0)
			(size 0.3048 0.381)
			(layers "B.Cu" "B.Mask" "B.Paste")
			(net "SMB_RT_CPU1_P1_ROM_MUX_2D_SCL")
		)
		(pad "2" smd rect
			(at -0.2667 0 180)
			(size 0.3048 0.381)
			(layers "B.Cu" "B.Mask" "B.Paste")
			(net "SMB_RT_CPU1_P1_ROM_MUX_2D_R_SCL")
		)
	)
	(footprint ""
		(layer "B.Cu")
		(at 74.947272 -390.587484)
		(property "Reference" "C320"
			(at 0 0 0)
			(layer "B.SilkS")
			(hide yes)
			(effects
				(font
					(size 1.27 1.27)
				)
				(justify mirror)
			)
		)
		(property "Value" ""
			(at 0 0 0)
			(layer "B.Fab")
			(effects
				(font
					(size 1.27 1.27)
				)
				(justify mirror)
			)
		)
		(duplicate_pad_numbers_are_jumpers no)
		(fp_line
			(start -1.524 -0.762)
			(end -1.524 0.762)
			(stroke
				(width 0.1524)
				(type default)
			)
			(layer "B.SilkS")
		)
		(fp_line
			(start -1.524 0.762)
			(end 1.524 0.762)
			(stroke
				(width 0.1524)
				(type default)
			)
			(layer "B.SilkS")
		)
		(fp_line
			(start 1.524 -0.762)
			(end -1.524 -0.762)
			(stroke
				(width 0.1524)
				(type default)
			)
			(layer "B.SilkS")
		)
		(fp_line
			(start 1.524 0.762)
			(end 1.524 -0.762)
			(stroke
				(width 0.1524)
				(type default)
			)
			(layer "B.SilkS")
		)
		(fp_line
			(start -1.1049 -0.724916)
			(end 1.1049 -0.724916)
			(stroke
				(width 0.1)
				(type default)
			)
			(layer "B.Fab")
		)
		(fp_line
			(start -1.1049 0.724916)
			(end -1.1049 -0.724916)
			(stroke
				(width 0.1)
				(type default)
			)
			(layer "B.Fab")
		)
		(fp_line
			(start 1.1049 -0.724916)
			(end 1.1049 0.724916)
			(stroke
				(width 0.1)
				(type default)
			)
			(layer "B.Fab")
		)
		(fp_line
			(start 1.1049 0.724916)
			(end -1.1049 0.724916)
			(stroke
				(width 0.1)
				(type default)
			)
			(layer "B.Fab")
		)
		(pad "1" smd rect
			(at 0.889 0)
			(size 1.016 1.27)
			(layers "B.Cu" "B.Mask" "B.Paste")
			(net "P0V9_CPU1_RT1_2A")
		)
		(pad "2" smd rect
			(at -0.889 0)
			(size 1.016 1.27)
			(layers "B.Cu" "B.Mask" "B.Paste")
			(net "GND")
		)
	)
	(footprint ""
		(layer "B.Cu")
		(at 359.994454 -267.52931 -90)
		(property "Reference" "C2244"
			(at 0 0 90)
			(layer "B.SilkS")
			(hide yes)
			(effects
				(font
					(size 1.27 1.27)
				)
				(justify mirror)
			)
		)
		(property "Value" ""
			(at 0 0 90)
			(layer "B.Fab")
			(effects
				(font
					(size 1.27 1.27)
				)
				(justify mirror)
			)
		)
		(duplicate_pad_numbers_are_jumpers no)
		(fp_line
			(start -0.7874 0.4064)
			(end 0.7874 0.4064)
			(stroke
				(width 0.1524)
				(type default)
			)
			(layer "B.SilkS")
		)
		(fp_line
			(start 0.7874 0.4064)
			(end 0.7874 -0.4064)
			(stroke
				(width 0.1524)
				(type default)
			)
			(layer "B.SilkS")
		)
		(fp_line
			(start -0.7874 -0.4064)
			(end -0.7874 0.4064)
			(stroke
				(width 0.1524)
				(type default)
			)
			(layer "B.SilkS")
		)
		(fp_line
			(start 0.7874 -0.4064)
			(end -0.7874 -0.4064)
			(stroke
				(width 0.1524)
				(type default)
			)
			(layer "B.SilkS")
		)
		(fp_line
			(start -0.67945 0.3048)
			(end -0.120396 0.3048)
			(stroke
				(width 0.1)
				(type default)
			)
			(layer "B.Fab")
		)
		(fp_line
			(start -0.120396 0.3048)
			(end -0.120396 0.2794)
			(stroke
				(width 0.1)
				(type default)
			)
			(layer "B.Fab")
		)
		(fp_line
			(start 0.12065 0.3048)
			(end 0.67945 0.3048)
			(stroke
				(width 0.1)
				(type default)
			)
			(layer "B.Fab")
		)
		(fp_line
			(start 0.67945 0.3048)
			(end 0.67945 -0.305054)
			(stroke
				(width 0.1)
				(type default)
			)
			(layer "B.Fab")
		)
		(fp_line
			(start -0.120396 0.2794)
			(end 0.12065 0.2794)
			(stroke
				(width 0.1)
				(type default)
			)
			(layer "B.Fab")
		)
		(fp_line
			(start 0.12065 0.2794)
			(end 0.12065 0.3048)
			(stroke
				(width 0.1)
				(type default)
			)
			(layer "B.Fab")
		)
		(fp_line
			(start -0.12065 -0.2794)
			(end -0.12065 -0.3048)
			(stroke
				(width 0.1)
				(type default)
			)
			(layer "B.Fab")
		)
		(fp_line
			(start 0.12065 -0.2794)
			(end -0.12065 -0.2794)
			(stroke
				(width 0.1)
				(type default)
			)
			(layer "B.Fab")
		)
		(fp_line
			(start -0.67945 -0.3048)
			(end -0.67945 0.3048)
			(stroke
				(width 0.1)
				(type default)
			)
			(layer "B.Fab")
		)
		(fp_line
			(start -0.12065 -0.3048)
			(end -0.67945 -0.3048)
			(stroke
				(width 0.1)
				(type default)
			)
			(layer "B.Fab")
		)
		(fp_line
			(start 0.12065 -0.305054)
			(end 0.12065 -0.2794)
			(stroke
				(width 0.1)
				(type default)
			)
			(layer "B.Fab")
		)
		(fp_line
			(start 0.67945 -0.305054)
			(end 0.12065 -0.305054)
			(stroke
				(width 0.1)
				(type default)
			)
			(layer "B.Fab")
		)
		(pad "1" smd circle
			(at 0.40005 0 90)
			(size 0 0)
			(layers "B.Cu" "B.Mask" "B.Paste")
			(net "PVDDCR_CPU1_P0")
		)
		(pad "2" smd circle
			(at -0.40005 0 90)
			(size 0 0)
			(layers "B.Cu" "B.Mask" "B.Paste")
			(net "GND")
		)
	)
	(footprint ""
		(layer "B.Cu")
		(at 186.711844 -117.442996 90)
		(property "Reference" "C1133"
			(at 0 0 90)
			(layer "B.SilkS")
			(hide yes)
			(effects
				(font
					(size 1.27 1.27)
				)
				(justify mirror)
			)
		)
		(property "Value" ""
			(at 0 0 90)
			(layer "B.Fab")
			(effects
				(font
					(size 1.27 1.27)
				)
				(justify mirror)
			)
		)
		(duplicate_pad_numbers_are_jumpers no)
		(fp_line
			(start 0.69215 -0.2921)
			(end -0.69215 -0.2921)
			(stroke
				(width 0.1524)
				(type default)
			)
			(layer "B.SilkS")
		)
		(fp_line
			(start -0.69215 -0.2921)
			(end -0.69215 0.2921)
			(stroke
				(width 0.1524)
				(type default)
			)
			(layer "B.SilkS")
		)
		(fp_line
			(start 0.69215 0.2921)
			(end 0.69215 -0.2921)
			(stroke
				(width 0.1524)
				(type default)
			)
			(layer "B.SilkS")
		)
		(fp_line
			(start -0.69215 0.2921)
			(end 0.69215 0.2921)
			(stroke
				(width 0.1524)
				(type default)
			)
			(layer "B.SilkS")
		)
		(fp_line
			(start 0.51435 -0.2794)
			(end -0.51435 -0.2794)
			(stroke
				(width 0.1)
				(type default)
			)
			(layer "B.Fab")
		)
		(fp_line
			(start -0.51435 -0.2794)
			(end -0.51435 0.2794)
			(stroke
				(width 0.1)
				(type default)
			)
			(layer "B.Fab")
		)
		(fp_line
			(start 0.51435 0.2794)
			(end 0.51435 -0.2794)
			(stroke
				(width 0.1)
				(type default)
			)
			(layer "B.Fab")
		)
		(fp_line
			(start -0.51435 0.2794)
			(end 0.51435 0.2794)
			(stroke
				(width 0.1)
				(type default)
			)
			(layer "B.Fab")
		)
		(pad "1" smd circle
			(at 0.40005 0 270)
			(size 0 0)
			(layers "B.Cu" "B.Mask" "B.Paste")
			(net "P1V8_AUX")
		)
		(pad "2" smd circle
			(at -0.40005 0 270)
			(size 0 0)
			(layers "B.Cu" "B.Mask" "B.Paste")
			(net "GND")
		)
		(zone
			(layer "B.Cu")
			(hatch none 0.5)
			(connect_pads
				(clearance 0)
			)
			(min_thickness 0.25)
			(keepout
				(tracks not_allowed)
				(vias allowed)
				(pads allowed)
				(copperpour not_allowed)
				(footprints allowed)
			)
			(placement
				(enabled no)
				(sheetname "")
			)
			(fill
				(thermal_gap 0.5)
				(thermal_bridge_width 0.5)
				(island_removal_mode 0)
			)
			(polygon
				(pts
					(xy 186.565794 -117.342666) (xy 186.565794 -117.542056) (xy 186.62396 -117.633496) (xy 186.799474 -117.633496)
					(xy 186.85764 -117.542056) (xy 186.85764 -117.342666) (xy 186.799474 -117.252496) (xy 186.624214 -117.252496)
				)
			)
		)
	)
)
